(kicad_pcb
	(version 20211014)
	(generator pcbnew)
	(general
    (thickness 1.6)
  )
	(paper "A4")
	(title_block
    (title "SA800U (Snapdragon 845) Baseboard")
    (date "2023-10-19")
    (rev "1.0.3")
    (company "Antmicro Ltd.")
    (comment 1 "www.antmicro.com")
		(comment 9 "footprints 157-165 of 589")
	)
	(layers
    (0 "F.Cu" signal)
    (1 "In1.Cu" power)
    (2 "In2.Cu" signal)
    (3 "In3.Cu" signal)
    (4 "In4.Cu" power)
    (31 "B.Cu" signal)
    (32 "B.Adhes" user "B.Adhesive")
    (33 "F.Adhes" user "F.Adhesive")
    (34 "B.Paste" user)
    (35 "F.Paste" user)
    (36 "B.SilkS" user "B.Silkscreen")
    (37 "F.SilkS" user "F.Silkscreen")
    (38 "B.Mask" user)
    (39 "F.Mask" user)
    (40 "Dwgs.User" user "User.Drawings")
    (41 "Cmts.User" user "User.Comments")
    (42 "Eco1.User" user "User.Eco1")
    (43 "Eco2.User" user "User.Eco2")
    (44 "Edge.Cuts" user)
    (45 "Margin" user)
    (46 "B.CrtYd" user "B.Courtyard")
    (47 "F.CrtYd" user "F.Courtyard")
    (48 "B.Fab" user)
    (49 "F.Fab" user)
  )
	(footprint "sa800u-baseboard-hw-footprints:LED_0603_1608Metric_G" (layer "F.Cu")
    (tedit 60C2DD7B)
    (at 83.45 124)
    (descr "LED SMD 0603 Green")
    (tags "LED SMD 0603 Green")
    (property "Author" "Antmicro")
    (property "License" "Apache-2.0")
    (property "MPN" "KP-1608ZGC")
    (property "Manufacturer" "Kingbright")
    (property "Sheetfile" "psu.kicad_sch")
    (property "Sheetname" "PSU")
    (attr smd)
    (fp_text reference "D28" (at -0.9 -0.47) (layer "F.SilkS")
      (effects (font (size 0.7 0.7) (thickness 0.15)) (justify left bottom))
    )
    (fp_text value "KP-1608EC" (at 0 1.6) (layer "F.Fab")
      (effects (font (size 0.7 0.7) (thickness 0.15)) (justify left bottom))
    )
    (fp_text user "Author: Antmicro" (at -1.31 4.769) (layer "F.Fab") hide
      (effects (font (size 0.7 0.7) (thickness 0.15)) (justify left bottom))
    )
    (fp_text user "License: Apache-2.0" (at -1.31 5.769) (layer "F.Fab") hide
      (effects (font (size 0.7 0.7) (thickness 0.15)) (justify left bottom))
    )
    (fp_text user "${REFERENCE}" (at -1.31 3.769) (layer "F.Fab") hide
      (effects (font (size 0.7 0.7) (thickness 0.15)) (justify left bottom))
    )
    (fp_line (start 0.093672 -0.000008) (end 0.293672 -0.000008) (layer "F.SilkS") (width 0.1))
    (fp_line (start -0.106328 -0.200008) (end -0.106328 0.199992) (layer "F.SilkS") (width 0.1))
    (fp_line (start 0.093672 -0.000008) (end -0.106328 0.199992) (layer "F.SilkS") (width 0.1))
    (fp_line (start -0.27 -0.35) (end 0.27 -0.35) (layer "F.SilkS") (width 0.15))
    (fp_line (start -0.27 0.351) (end 0.27 0.351) (layer "F.SilkS") (width 0.15))
    (fp_line (start 0.093672 -0.200008) (end 0.093672 0.199992) (layer "F.SilkS") (width 0.1))
    (fp_line (start -0.106328 -0.000008) (end -0.29 0) (layer "F.SilkS") (width 0.1))
    (fp_line (start -0.106328 -0.200008) (end 0.093672 -0.000008) (layer "F.SilkS") (width 0.1))
    (fp_line (start 1.25 0.32) (end 1.25 -0.32) (layer "F.SilkS") (width 0.15))
    (fp_rect (start 1.26 0.65) (end -1.26 -0.65) (layer "F.CrtYd") (width 0.05) (fill none))
    (fp_line (start 0.199 -0.2) (end 0.199 -0.1) (layer "F.Fab") (width 0.15))
    (fp_line (start -0.201 -0.2) (end -0.201 0) (layer "F.Fab") (width 0.15))
    (fp_line (start -0.201 0) (end -0.201 0.202) (layer "F.Fab") (width 0.15))
    (fp_line (start 0.199 0.202) (end 0.199 -0.1) (layer "F.Fab") (width 0.15))
    (fp_line (start -0.599 0) (end -0.201 0) (layer "F.Fab") (width 0.15))
    (fp_line (start -0.201 0.202) (end 0.101 0) (layer "F.Fab") (width 0.15))
    (fp_line (start 0.199 0) (end 0.597 0) (layer "F.Fab") (width 0.15))
    (fp_line (start 0.101 0) (end -0.201 -0.2) (layer "F.Fab") (width 0.15))
    (fp_rect (start -0.848 -0.4) (end 0.85 0.402) (layer "F.Fab") (width 0.15) (fill none))
    (pad "1" smd rect (at -0.75 0 180) (size 0.8 0.8) (layers "F.Cu" "F.Paste" "F.Mask")
      (net 74 "VDD") (pinfunction "1") (pintype "passive"))
    (pad "2" smd rect (at 0.75 0 180) (size 0.8 0.8) (layers "F.Cu" "F.Paste" "F.Mask")
      (net 342 "Net-(D28-Pad2)") (pinfunction "2") (pintype "passive"))
  )
	(footprint "sa800u-baseboard-hw-footprints:R_0402_1005Metric" (layer "F.Cu")
    (tedit 5FD9C158)
    (at 85.45 123.7 -90)
    (descr "Resistor SMD 0402")
    (tags "resistor SMD 0402")
    (property "Author" "Antmicro")
    (property "License" "Apache-2.0")
    (property "MPN" "CR0402-FX-1002GLF")
    (property "Manufacturer" "Bourns")
    (property "Sheetfile" "psu.kicad_sch")
    (property "Sheetname" "PSU")
    (property "Tolerance" "1%")
    (property "Val" "10k")
    (attr smd)
    (fp_text reference "R122" (at 1.11 -1.4 -90) (layer "F.SilkS")
      (effects (font (size 0.7 0.7) (thickness 0.15)) (justify left bottom))
    )
    (fp_text value "R_10k_0402" (at 0 1.4 -90) (layer "F.Fab")
      (effects (font (size 0.7 0.7) (thickness 0.15)) (justify left bottom))
    )
    (fp_text user "Author: Antmicro" (at -0.95 4.169 -90) (layer "F.Fab") hide
      (effects (font (size 0.7 0.7) (thickness 0.15)) (justify left bottom))
    )
    (fp_text user "${REFERENCE}" (at -0.95 3.168 -90) (layer "F.Fab") hide
      (effects (font (size 0.7 0.7) (thickness 0.15)) (justify left bottom))
    )
    (fp_text user "License: Apache-2.0" (at -0.95 5.169 -90) (layer "F.Fab") hide
      (effects (font (size 0.7 0.7) (thickness 0.15)) (justify left bottom))
    )
    (fp_rect (start -0.93 -0.47) (end 0.93 0.47) (layer "F.CrtYd") (width 0.05) (fill none))
    (fp_rect (start -0.5 -0.25) (end 0.5 0.25) (layer "F.Fab") (width 0.15) (fill none))
    (pad "1" smd roundrect (at -0.485 0 270) (size 0.59 0.64) (layers "F.Cu" "F.Paste" "F.Mask") (roundrect_rratio 0.25)
      (net 348 "Net-(Q14-Pad3)") (pintype "passive"))
    (pad "2" smd roundrect (at 0.485 0 270) (size 0.59 0.64) (layers "F.Cu" "F.Paste" "F.Mask") (roundrect_rratio 0.25)
      (net 342 "Net-(D28-Pad2)") (pintype "passive"))
  )
	(footprint "sa800u-baseboard-hw-footprints:R_0402_1005Metric" (layer "F.Cu")
    (tedit 5FD9C158)
    (at 76 137.3 180)
    (descr "Resistor SMD 0402")
    (tags "resistor SMD 0402")
    (property "Author" "Antmicro")
    (property "License" "Apache-2.0")
    (property "MPN" "CR0402-FX-1004GLF")
    (property "Manufacturer" "Bourns")
    (property "Sheetfile" "psu.kicad_sch")
    (property "Sheetname" "PSU")
    (property "Tolerance" "1%")
    (property "Val" "1M")
    (attr smd)
    (fp_text reference "R120" (at 1.46 -2.38 180) (layer "F.SilkS")
      (effects (font (size 0.7 0.7) (thickness 0.15)) (justify left bottom))
    )
    (fp_text value "R_1M_0402" (at 0 1.4 180) (layer "F.Fab")
      (effects (font (size 0.7 0.7) (thickness 0.15)) (justify left bottom))
    )
    (fp_text user "License: Apache-2.0" (at -0.95 5.169 180) (layer "F.Fab") hide
      (effects (font (size 0.7 0.7) (thickness 0.15)) (justify left bottom))
    )
    (fp_text user "Author: Antmicro" (at -0.95 4.169 180) (layer "F.Fab") hide
      (effects (font (size 0.7 0.7) (thickness 0.15)) (justify left bottom))
    )
    (fp_text user "${REFERENCE}" (at -0.95 3.168 180) (layer "F.Fab") hide
      (effects (font (size 0.7 0.7) (thickness 0.15)) (justify left bottom))
    )
    (fp_rect (start -0.93 -0.47) (end 0.93 0.47) (layer "F.CrtYd") (width 0.05) (fill none))
    (fp_rect (start -0.5 -0.25) (end 0.5 0.25) (layer "F.Fab") (width 0.15) (fill none))
    (pad "1" smd roundrect (at -0.485 0 180) (size 0.59 0.64) (layers "F.Cu" "F.Paste" "F.Mask") (roundrect_rratio 0.25)
      (net 74 "VDD") (pintype "passive"))
    (pad "2" smd roundrect (at 0.485 0 180) (size 0.59 0.64) (layers "F.Cu" "F.Paste" "F.Mask") (roundrect_rratio 0.25)
      (net 339 "/PSU/AUX_VALID") (pintype "passive"))
  )
	(footprint "sa800u-baseboard-hw-footprints:R_0402_1005Metric" (layer "F.Cu")
    (tedit 5FD9C158)
    (at 76 136.3 180)
    (descr "Resistor SMD 0402")
    (tags "resistor SMD 0402")
    (property "Author" "Antmicro")
    (property "License" "Apache-2.0")
    (property "MPN" "CR0402-FX-1004GLF")
    (property "Manufacturer" "Bourns")
    (property "Sheetfile" "psu.kicad_sch")
    (property "Sheetname" "PSU")
    (property "Tolerance" "1%")
    (property "Val" "1M")
    (attr smd)
    (fp_text reference "R119" (at 1.46 -2.38 180) (layer "F.SilkS")
      (effects (font (size 0.7 0.7) (thickness 0.15)) (justify left bottom))
    )
    (fp_text value "R_1M_0402" (at 0 1.4 180) (layer "F.Fab")
      (effects (font (size 0.7 0.7) (thickness 0.15)) (justify left bottom))
    )
    (fp_text user "License: Apache-2.0" (at -0.95 5.169 180) (layer "F.Fab") hide
      (effects (font (size 0.7 0.7) (thickness 0.15)) (justify left bottom))
    )
    (fp_text user "Author: Antmicro" (at -0.95 4.169 180) (layer "F.Fab") hide
      (effects (font (size 0.7 0.7) (thickness 0.15)) (justify left bottom))
    )
    (fp_text user "${REFERENCE}" (at -0.95 3.168 180) (layer "F.Fab") hide
      (effects (font (size 0.7 0.7) (thickness 0.15)) (justify left bottom))
    )
    (fp_rect (start -0.93 -0.47) (end 0.93 0.47) (layer "F.CrtYd") (width 0.05) (fill none))
    (fp_rect (start -0.5 -0.25) (end 0.5 0.25) (layer "F.Fab") (width 0.15) (fill none))
    (pad "1" smd roundrect (at -0.485 0 180) (size 0.59 0.64) (layers "F.Cu" "F.Paste" "F.Mask") (roundrect_rratio 0.25)
      (net 74 "VDD") (pintype "passive"))
    (pad "2" smd roundrect (at 0.485 0 180) (size 0.59 0.64) (layers "F.Cu" "F.Paste" "F.Mask") (roundrect_rratio 0.25)
      (net 341 "/PSU/USB_PD_VALID") (pintype "passive"))
  )
	(footprint "sa800u-baseboard-hw-footprints:R_0402_1005Metric" (layer "F.Cu")
    (tedit 5FD9C158)
    (at 86.9 103.7 -90)
    (descr "Resistor SMD 0402")
    (tags "resistor SMD 0402")
    (property "Author" "Antmicro")
    (property "License" "Apache-2.0")
    (property "MPN" "CR0402-FX-1004GLF")
    (property "Manufacturer" "Bourns")
    (property "Sheetfile" "psu.kicad_sch")
    (property "Sheetname" "PSU")
    (property "Tolerance" "1%")
    (property "Val" "1M")
    (attr smd)
    (fp_text reference "R118" (at 1.63 -1.44 -90) (layer "F.SilkS")
      (effects (font (size 0.7 0.7) (thickness 0.15)) (justify left bottom))
    )
    (fp_text value "R_1M_0402" (at 0 1.4 -90) (layer "F.Fab")
      (effects (font (size 0.7 0.7) (thickness 0.15)) (justify left bottom))
    )
    (fp_text user "Author: Antmicro" (at -0.95 4.169 -90) (layer "F.Fab") hide
      (effects (font (size 0.7 0.7) (thickness 0.15)) (justify left bottom))
    )
    (fp_text user "${REFERENCE}" (at -0.95 3.168 -90) (layer "F.Fab") hide
      (effects (font (size 0.7 0.7) (thickness 0.15)) (justify left bottom))
    )
    (fp_text user "License: Apache-2.0" (at -0.95 5.169 -90) (layer "F.Fab") hide
      (effects (font (size 0.7 0.7) (thickness 0.15)) (justify left bottom))
    )
    (fp_rect (start -0.93 -0.47) (end 0.93 0.47) (layer "F.CrtYd") (width 0.05) (fill none))
    (fp_rect (start -0.5 -0.25) (end 0.5 0.25) (layer "F.Fab") (width 0.15) (fill none))
    (pad "1" smd roundrect (at -0.485 0 270) (size 0.59 0.64) (layers "F.Cu" "F.Paste" "F.Mask") (roundrect_rratio 0.25)
      (net 74 "VDD") (pintype "passive"))
    (pad "2" smd roundrect (at 0.485 0 270) (size 0.59 0.64) (layers "F.Cu" "F.Paste" "F.Mask") (roundrect_rratio 0.25)
      (net 340 "/PSU/POE_VALID") (pintype "passive"))
  )
	(footprint "sa800u-baseboard-hw-footprints:R_0402_1005Metric" (layer "F.Cu")
    (tedit 5FD9C158)
    (at 95.15 128 180)
    (descr "Resistor SMD 0402")
    (tags "resistor SMD 0402")
    (property "Author" "Antmicro")
    (property "Current" "1A")
    (property "License" "Apache-2.0")
    (property "MPN" "ERJ2GE0R00X")
    (property "Manufacturer" "Panasonic")
    (property "Sheetfile" "usb-pd.kicad_sch")
    (property "Sheetname" "USB-PD")
    (property "Tolerance" "")
    (property "Val" "0R")
    (attr smd)
    (fp_text reference "R165" (at -0.9 -0.44 180) (layer "F.SilkS")
      (effects (font (size 0.7 0.7) (thickness 0.15)) (justify left bottom))
    )
    (fp_text value "R_0R_0402" (at 0 1.4 180) (layer "F.Fab")
      (effects (font (size 0.7 0.7) (thickness 0.15)) (justify left bottom))
    )
    (fp_text user "${REFERENCE}" (at -0.95 3.168 180) (layer "F.Fab") hide
      (effects (font (size 0.7 0.7) (thickness 0.15)) (justify left bottom))
    )
    (fp_text user "License: Apache-2.0" (at -0.95 5.169 180) (layer "F.Fab") hide
      (effects (font (size 0.7 0.7) (thickness 0.15)) (justify left bottom))
    )
    (fp_text user "Author: Antmicro" (at -0.95 4.169 180) (layer "F.Fab") hide
      (effects (font (size 0.7 0.7) (thickness 0.15)) (justify left bottom))
    )
    (fp_rect (start -0.93 -0.47) (end 0.93 0.47) (layer "F.CrtYd") (width 0.05) (fill none))
    (fp_rect (start -0.5 -0.25) (end 0.5 0.25) (layer "F.Fab") (width 0.15) (fill none))
    (pad "1" smd roundrect (at -0.485 0 180) (size 0.59 0.64) (layers "F.Cu" "F.Paste" "F.Mask") (roundrect_rratio 0.25)
      (net 167 "STUSB4500_ATTACH") (pintype "passive"))
    (pad "2" smd roundrect (at 0.485 0 180) (size 0.59 0.64) (layers "F.Cu" "F.Paste" "F.Mask") (roundrect_rratio 0.25)
      (net 335 "/USB-PD/ATTACH") (pintype "passive"))
  )
	(footprint "sa800u-baseboard-hw-footprints:R_0402_1005Metric" (layer "F.Cu")
    (tedit 5FD9C158)
    (at 95.15 126 180)
    (descr "Resistor SMD 0402")
    (tags "resistor SMD 0402")
    (property "Author" "Antmicro")
    (property "Current" "1A")
    (property "License" "Apache-2.0")
    (property "MPN" "ERJ2GE0R00X")
    (property "Manufacturer" "Panasonic")
    (property "Sheetfile" "usb-pd.kicad_sch")
    (property "Sheetname" "USB-PD")
    (property "Tolerance" "")
    (property "Val" "0R")
    (attr smd)
    (fp_text reference "R164" (at -0.9 -0.44 180) (layer "F.SilkS")
      (effects (font (size 0.7 0.7) (thickness 0.15)) (justify left bottom))
    )
    (fp_text value "R_0R_0402" (at 0 1.4 180) (layer "F.Fab")
      (effects (font (size 0.7 0.7) (thickness 0.15)) (justify left bottom))
    )
    (fp_text user "License: Apache-2.0" (at -0.95 5.169 180) (layer "F.Fab") hide
      (effects (font (size 0.7 0.7) (thickness 0.15)) (justify left bottom))
    )
    (fp_text user "Author: Antmicro" (at -0.95 4.169 180) (layer "F.Fab") hide
      (effects (font (size 0.7 0.7) (thickness 0.15)) (justify left bottom))
    )
    (fp_text user "${REFERENCE}" (at -0.95 3.168 180) (layer "F.Fab") hide
      (effects (font (size 0.7 0.7) (thickness 0.15)) (justify left bottom))
    )
    (fp_rect (start -0.93 -0.47) (end 0.93 0.47) (layer "F.CrtYd") (width 0.05) (fill none))
    (fp_rect (start -0.5 -0.25) (end 0.5 0.25) (layer "F.Fab") (width 0.15) (fill none))
    (pad "1" smd roundrect (at -0.485 0 180) (size 0.59 0.64) (layers "F.Cu" "F.Paste" "F.Mask") (roundrect_rratio 0.25)
      (net 166 "STUSB4500_GPIO") (pintype "passive"))
    (pad "2" smd roundrect (at 0.485 0 180) (size 0.59 0.64) (layers "F.Cu" "F.Paste" "F.Mask") (roundrect_rratio 0.25)
      (net 334 "/USB-PD/GPIO") (pintype "passive"))
  )
	(footprint "sa800u-baseboard-hw-footprints:R_0402_1005Metric" (layer "F.Cu")
    (tedit 5FD9C158)
    (at 95.15 127 180)
    (descr "Resistor SMD 0402")
    (tags "resistor SMD 0402")
    (property "Author" "Antmicro")
    (property "Current" "1A")
    (property "License" "Apache-2.0")
    (property "MPN" "ERJ2GE0R00X")
    (property "Manufacturer" "Panasonic")
    (property "Sheetfile" "usb-pd.kicad_sch")
    (property "Sheetname" "USB-PD")
    (property "Tolerance" "")
    (property "Val" "0R")
    (attr smd)
    (fp_text reference "R163" (at -0.9 -0.44 180) (layer "F.SilkS")
      (effects (font (size 0.7 0.7) (thickness 0.15)) (justify left bottom))
    )
    (fp_text value "R_0R_0402" (at 0 1.4 180) (layer "F.Fab")
      (effects (font (size 0.7 0.7) (thickness 0.15)) (justify left bottom))
    )
    (fp_text user "Author: Antmicro" (at -0.95 4.169 180) (layer "F.Fab") hide
      (effects (font (size 0.7 0.7) (thickness 0.15)) (justify left bottom))
    )
    (fp_text user "License: Apache-2.0" (at -0.95 5.169 180) (layer "F.Fab") hide
      (effects (font (size 0.7 0.7) (thickness 0.15)) (justify left bottom))
    )
    (fp_text user "${REFERENCE}" (at -0.95 3.168 180) (layer "F.Fab") hide
      (effects (font (size 0.7 0.7) (thickness 0.15)) (justify left bottom))
    )
    (fp_rect (start -0.93 -0.47) (end 0.93 0.47) (layer "F.CrtYd") (width 0.05) (fill none))
    (fp_rect (start -0.5 -0.25) (end 0.5 0.25) (layer "F.Fab") (width 0.15) (fill none))
    (pad "1" smd roundrect (at -0.485 0 180) (size 0.59 0.64) (layers "F.Cu" "F.Paste" "F.Mask") (roundrect_rratio 0.25)
      (net 165 "STUSB4500_AB_SIDE") (pintype "passive"))
    (pad "2" smd roundrect (at 0.485 0 180) (size 0.59 0.64) (layers "F.Cu" "F.Paste" "F.Mask") (roundrect_rratio 0.25)
      (net 333 "/USB-PD/AB_SIDE") (pintype "passive"))
  )
	(footprint "sa800u-baseboard-hw-footprints:R_0402_1005Metric" (layer "F.Cu")
    (tedit 5FD9C158)
    (at 95.15 129 180)
    (descr "Resistor SMD 0402")
    (tags "resistor SMD 0402")
    (property "Author" "Antmicro")
    (property "Current" "1A")
    (property "License" "Apache-2.0")
    (property "MPN" "ERJ2GE0R00X")
    (property "Manufacturer" "Panasonic")
    (property "Sheetfile" "usb-pd.kicad_sch")
    (property "Sheetname" "USB-PD")
    (property "Tolerance" "")
    (property "Val" "0R")
    (attr smd)
    (fp_text reference "R162" (at -0.9 -0.44 180) (layer "F.SilkS")
      (effects (font (size 0.7 0.7) (thickness 0.15)) (justify left bottom))
    )
    (fp_text value "R_0R_0402" (at 0 1.4 180) (layer "F.Fab")
      (effects (font (size 0.7 0.7) (thickness 0.15)) (justify left bottom))
    )
    (fp_text user "${REFERENCE}" (at -0.95 3.168 180) (layer "F.Fab") hide
      (effects (font (size 0.7 0.7) (thickness 0.15)) (justify left bottom))
    )
    (fp_text user "Author: Antmicro" (at -0.95 4.169 180) (layer "F.Fab") hide
      (effects (font (size 0.7 0.7) (thickness 0.15)) (justify left bottom))
    )
    (fp_text user "License: Apache-2.0" (at -0.95 5.169 180) (layer "F.Fab") hide
      (effects (font (size 0.7 0.7) (thickness 0.15)) (justify left bottom))
    )
    (fp_rect (start -0.93 -0.47) (end 0.93 0.47) (layer "F.CrtYd") (width 0.05) (fill none))
    (fp_rect (start -0.5 -0.25) (end 0.5 0.25) (layer "F.Fab") (width 0.15) (fill none))
    (pad "1" smd roundrect (at -0.485 0 180) (size 0.59 0.64) (layers "F.Cu" "F.Paste" "F.Mask") (roundrect_rratio 0.25)
      (net 168 "STUSB4500_ALERT") (pintype "passive"))
    (pad "2" smd roundrect (at 0.485 0 180) (size 0.59 0.64) (layers "F.Cu" "F.Paste" "F.Mask") (roundrect_rratio 0.25)
      (net 332 "/USB-PD/ALERT") (pintype "passive"))
  )
)
